# SCM (Grand Teton) — schematic netlist excerpt (pin names and nets, part order shuffled) for the footprints in the layout excerpt that follows; sources: Cadence DE-HDL packaged netlist, KiCad conversion of 12092022_DA0F0TMDCD0_F0T_Management_Board_D_brd_V3_OCP.brd

C249  Q_CAP  0.1UF 25V 10% X7R  pkg 0402  page 46 : A = P3V3_AUX ; B = GND

(kicad_pcb
	(version 20260206)
	(generator "pcbnew")
	(generator_version "10.0")
	(general
		(thickness 1.6)
		(legacy_teardrops no)
	)
	(paper "A4")
	(title_block
		(title "12092022_DA0F0TMDCD0_F0T_Management_Board_D_brd_V3_OCP.brd")
		(comment 1 "Grand Teton / footprints 803-803 of 1440")
	)
	(layers
		(0 "F.Cu" signal "TOP")
		(4 "In1.Cu" signal "GND")
		(6 "In2.Cu" signal "IN1")
		(8 "In3.Cu" signal "GND1")
		(10 "In4.Cu" signal "IN2")
		(12 "In5.Cu" signal "VCC")
		(14 "In6.Cu" signal "VCC1")
		(16 "In7.Cu" signal "IN3")
		(18 "In8.Cu" signal "GND2")
		(20 "In9.Cu" signal "IN4")
		(22 "In10.Cu" signal "GND3")
		(2 "B.Cu" signal "BOTTOM")
		(9 "F.Adhes" user "F.Adhesive")
		(11 "B.Adhes" user "B.Adhesive")
		(13 "F.Paste" user "Package Geometry/Pastemask Top")
		(15 "B.Paste" user "Package Geometry/Pastemask Bottom")
		(5 "F.SilkS" user "Ref Des/Silkscreen Top")
		(7 "B.SilkS" user "Ref Des/Silkscreen Bottom")
		(1 "F.Mask" user "Board Geometry/Soldermask Top")
		(3 "B.Mask" user "Board Geometry/Soldermask Bottom")
		(17 "Dwgs.User" user "User.Drawings")
		(19 "Cmts.User" user "User.Comments")
		(21 "Eco1.User" user "User.Eco1")
		(23 "Eco2.User" user "User.Eco2")
		(25 "Edge.Cuts" user "Board Geometry/Outline")
		(27 "Margin" user)
		(31 "F.CrtYd" user "Package Geometry/Place Bound Top")
		(29 "B.CrtYd" user "Package Geometry/Place Bound Bottom")
		(35 "F.Fab" user "Ref Des/Assembly Top")
		(33 "B.Fab" user "Ref Des/Assembly Bottom")
	)
	(footprint ""
		(layer "B.Cu")
		(at 84.452968 -98.20529 180)
		(property "Reference" "C249"
			(at 0 0 0)
			(layer "B.SilkS")
			(hide yes)
			(effects
				(font
					(size 1.27 1.27)
				)
				(justify mirror)
			)
		)
		(property "Value" ""
			(at 0 0 0)
			(layer "B.Fab")
			(effects
				(font
					(size 1.27 1.27)
				)
				(justify mirror)
			)
		)
		(duplicate_pad_numbers_are_jumpers no)
		(fp_line
			(start 0.7874 0.4064)
			(end 0.7874 -0.4064)
			(stroke
				(width 0.1524)
				(type default)
			)
			(layer "B.SilkS")
		)
		(fp_line
			(start 0.7874 -0.4064)
			(end -0.7874 -0.4064)
			(stroke
				(width 0.1524)
				(type default)
			)
			(layer "B.SilkS")
		)
		(fp_line
			(start -0.7874 0.4064)
			(end 0.7874 0.4064)
			(stroke
				(width 0.1524)
				(type default)
			)
			(layer "B.SilkS")
		)
		(fp_line
			(start -0.7874 -0.4064)
			(end -0.7874 0.4064)
			(stroke
				(width 0.1524)
				(type default)
			)
			(layer "B.SilkS")
		)
		(fp_line
			(start 0.67945 0.3048)
			(end 0.67945 -0.305054)
			(stroke
				(width 0.1)
				(type default)
			)
			(layer "B.Fab")
		)
		(fp_line
			(start 0.67945 -0.305054)
			(end 0.12065 -0.305054)
			(stroke
				(width 0.1)
				(type default)
			)
			(layer "B.Fab")
		)
		(fp_line
			(start 0.12065 0.3048)
			(end 0.67945 0.3048)
			(stroke
				(width 0.1)
				(type default)
			)
			(layer "B.Fab")
		)
		(fp_line
			(start 0.12065 0.2794)
			(end 0.12065 0.3048)
			(stroke
				(width 0.1)
				(type default)
			)
			(layer "B.Fab")
		)
		(fp_line
			(start 0.12065 -0.2794)
			(end -0.12065 -0.2794)
			(stroke
				(width 0.1)
				(type default)
			)
			(layer "B.Fab")
		)
		(fp_line
			(start 0.12065 -0.305054)
			(end 0.12065 -0.2794)
			(stroke
				(width 0.1)
				(type default)
			)
			(layer "B.Fab")
		)
		(fp_line
			(start -0.120396 0.3048)
			(end -0.120396 0.2794)
			(stroke
				(width 0.1)
				(type default)
			)
			(layer "B.Fab")
		)
		(fp_line
			(start -0.120396 0.2794)
			(end 0.12065 0.2794)
			(stroke
				(width 0.1)
				(type default)
			)
			(layer "B.Fab")
		)
		(fp_line
			(start -0.12065 -0.2794)
			(end -0.12065 -0.3048)
			(stroke
				(width 0.1)
				(type default)
			)
			(layer "B.Fab")
		)
		(fp_line
			(start -0.12065 -0.3048)
			(end -0.67945 -0.3048)
			(stroke
				(width 0.1)
				(type default)
			)
			(layer "B.Fab")
		)
		(fp_line
			(start -0.67945 0.3048)
			(end -0.120396 0.3048)
			(stroke
				(width 0.1)
				(type default)
			)
			(layer "B.Fab")
		)
		(fp_line
			(start -0.67945 -0.3048)
			(end -0.67945 0.3048)
			(stroke
				(width 0.1)
				(type default)
			)
			(layer "B.Fab")
		)
		(pad "1" smd circle
			(at 0.40005 0)
			(size 0 0)
			(layers "B.Cu" "B.Mask" "B.Paste")
			(net "P3V3_AUX")
		)
		(pad "2" smd circle
			(at -0.40005 0)
			(size 0 0)
			(layers "B.Cu" "B.Mask" "B.Paste")
			(net "GND")
		)
	)
)
